(kicad_pcb
	(version 20241229)
	(generator "pcbnew")
	(generator_version "9.0")
	(general
		(thickness 1.258)
		(legacy_teardrops no)
	)
	(paper "A4")
	(title_block
		(date "2024-05-27")
		(rev "1.1.2")
		(comment 9 "footprints 37-42 of 64")
	)
	(layers
		(0 "F.Cu" signal)
		(4 "In1.Cu" power)
		(6 "In2.Cu" power)
		(8 "In3.Cu" signal)
		(10 "In4.Cu" signal)
		(2 "B.Cu" signal)
		(9 "F.Adhes" user "F.Adhesive")
		(11 "B.Adhes" user "B.Adhesive")
		(13 "F.Paste" user)
		(15 "B.Paste" user)
		(5 "F.SilkS" user "F.Silkscreen")
		(7 "B.SilkS" user "B.Silkscreen")
		(1 "F.Mask" user)
		(3 "B.Mask" user)
		(17 "Dwgs.User" user "User.Drawings")
		(19 "Cmts.User" user "User.Comments")
		(21 "Eco1.User" user "User.Eco1")
		(23 "Eco2.User" user "User.Eco2")
		(25 "Edge.Cuts" user)
		(27 "Margin" user)
		(31 "F.CrtYd" user "F.Courtyard")
		(29 "B.CrtYd" user "B.Courtyard")
		(35 "F.Fab" user)
		(33 "B.Fab" user)
	)
	(footprint "antmicro-footprints:R_0402_1005Metric"
		(layer "F.Cu")
		(at 151.225 91.15 -90)
		(descr "Resistor SMD 0402")
		(tags "resistor SMD 0402")
		(property "Reference" "R17"
			(at 3.05 -0.385 270)
			(layer "F.SilkS")
			(effects
				(font
					(size 0.7 0.7)
					(thickness 0.15)
				)
				(justify left bottom)
			)
		)
		(property "Value" "R_0R_0402"
			(at 0 1.4 270)
			(layer "F.Fab")
			(hide yes)
			(effects
				(font
					(size 0.7 0.7)
					(thickness 0.15)
				)
				(justify left bottom)
			)
		)
		(property "Description" "0R resistor in 0402 package with unspecified tolerance"
			(at 0 0 270)
			(layer "F.Fab")
			(hide yes)
			(effects
				(font
					(size 1.27 1.27)
					(thickness 0.15)
				)
			)
		)
		(property "Author" "Antmicro"
			(at 60.075 242.375 0)
			(layer "F.Fab")
			(hide yes)
			(effects
				(font
					(size 1 1)
					(thickness 0.15)
				)
			)
		)
		(property "Current" "1A"
			(at 60.075 242.375 0)
			(layer "F.Fab")
			(hide yes)
			(effects
				(font
					(size 1 1)
					(thickness 0.15)
				)
			)
		)
		(property "License" "Apache-2.0"
			(at 60.075 242.375 0)
			(layer "F.Fab")
			(hide yes)
			(effects
				(font
					(size 1 1)
					(thickness 0.15)
				)
			)
		)
		(property "MPN" "ERJ2GE0R00X"
			(at 60.075 242.375 0)
			(layer "F.Fab")
			(hide yes)
			(effects
				(font
					(size 1 1)
					(thickness 0.15)
				)
			)
		)
		(property "Manufacturer" "Panasonic"
			(at 60.075 242.375 0)
			(layer "F.Fab")
			(hide yes)
			(effects
				(font
					(size 1 1)
					(thickness 0.15)
				)
			)
		)
		(property "Tolerance" ""
			(at 60.075 242.375 0)
			(layer "F.Fab")
			(hide yes)
			(effects
				(font
					(size 1 1)
					(thickness 0.15)
				)
			)
		)
		(property "Val" "0R"
			(at 60.075 242.375 0)
			(layer "F.Fab")
			(hide yes)
			(effects
				(font
					(size 1 1)
					(thickness 0.15)
				)
			)
		)
		(sheetname "DDR5")
		(sheetfile "ddr5.kicad_sch")
		(attr smd)
		(fp_rect
			(start -0.925 -0.47)
			(end 0.925 0.47)
			(stroke
				(width 0.05)
				(type default)
			)
			(fill no)
			(layer "F.CrtYd")
		)
		(fp_rect
			(start -0.5 -0.25)
			(end 0.5 0.25)
			(stroke
				(width 0.15)
				(type solid)
			)
			(fill no)
			(layer "F.Fab")
		)
		(pad "1" smd roundrect
			(at -0.48 0 270)
			(size 0.59 0.64)
			(layers "F.Cu" "F.Mask" "F.Paste")
			(roundrect_rratio 0.25)
			(net 64 "/DDR5/R_TEN")
			(pintype "passive")
		)
		(pad "2" smd roundrect
			(at 0.48 0 270)
			(size 0.59 0.64)
			(layers "F.Cu" "F.Mask" "F.Paste")
			(roundrect_rratio 0.25)
			(net 54 "TEN")
			(pintype "passive")
		)
	)
	(footprint "antmicro-footprints:R_0402_1005Metric"
		(layer "B.Cu")
		(at 151.15 85)
		(descr "Resistor SMD 0402")
		(tags "resistor SMD 0402")
		(property "Reference" "R3"
			(at 2.38 0.4 180)
			(layer "B.SilkS")
			(effects
				(font
					(size 0.7 0.7)
					(thickness 0.15)
				)
				(justify left bottom mirror)
			)
		)
		(property "Value" "R_10k_0402"
			(at 0 -1.4 180)
			(layer "B.Fab")
			(hide yes)
			(effects
				(font
					(size 0.7 0.7)
					(thickness 0.15)
				)
				(justify left bottom mirror)
			)
		)
		(property "Description" "10k resistor in 0402 package with 1% tolerance"
			(at 0 0 0)
			(layer "F.Fab")
			(hide yes)
			(effects
				(font
					(size 1.27 1.27)
					(thickness 0.15)
				)
			)
		)
		(property "Author" "Antmicro"
			(at 0 0 0)
			(layer "B.Fab")
			(hide yes)
			(effects
				(font
					(size 1 1)
					(thickness 0.15)
				)
				(justify mirror)
			)
		)
		(property "License" "Apache-2.0"
			(at 0 0 0)
			(layer "B.Fab")
			(hide yes)
			(effects
				(font
					(size 1 1)
					(thickness 0.15)
				)
				(justify mirror)
			)
		)
		(property "MPN" "CR0402-FX-1002GLF"
			(at 0 0 0)
			(layer "B.Fab")
			(hide yes)
			(effects
				(font
					(size 1 1)
					(thickness 0.15)
				)
				(justify mirror)
			)
		)
		(property "Manufacturer" "Bourns"
			(at 0 0 0)
			(layer "B.Fab")
			(hide yes)
			(effects
				(font
					(size 1 1)
					(thickness 0.15)
				)
				(justify mirror)
			)
		)
		(property "Tolerance" "1%"
			(at 0 0 0)
			(layer "B.Fab")
			(hide yes)
			(effects
				(font
					(size 1 1)
					(thickness 0.15)
				)
				(justify mirror)
			)
		)
		(property "Val" "10k"
			(at 0 0 0)
			(layer "B.Fab")
			(hide yes)
			(effects
				(font
					(size 1 1)
					(thickness 0.15)
				)
				(justify mirror)
			)
		)
		(sheetname "DDR5")
		(sheetfile "ddr5.kicad_sch")
		(attr smd)
		(fp_rect
			(start -0.925 0.47)
			(end 0.925 -0.47)
			(stroke
				(width 0.05)
				(type default)
			)
			(fill no)
			(layer "B.CrtYd")
		)
		(fp_rect
			(start -0.5 0.25)
			(end 0.5 -0.25)
			(stroke
				(width 0.15)
				(type solid)
			)
			(fill no)
			(layer "B.Fab")
		)
		(pad "1" smd roundrect
			(at -0.48 0)
			(size 0.59 0.64)
			(layers "B.Cu" "B.Mask" "B.Paste")
			(roundrect_rratio 0.25)
			(net 17 "CS_N")
			(pintype "passive")
		)
		(pad "2" smd roundrect
			(at 0.48 0)
			(size 0.59 0.64)
			(layers "B.Cu" "B.Mask" "B.Paste")
			(roundrect_rratio 0.25)
			(net 1 "GND")
			(pintype "passive")
		)
	)
	(footprint "antmicro-footprints:R_0402_1005Metric"
		(layer "B.Cu")
		(at 156.9 84.6 180)
		(descr "Resistor SMD 0402")
		(tags "resistor SMD 0402")
		(property "Reference" "R1"
			(at -2.39 -0.31 0)
			(layer "B.SilkS")
			(effects
				(font
					(size 0.7 0.7)
					(thickness 0.15)
				)
				(justify left bottom mirror)
			)
		)
		(property "Value" "R_1k_0402"
			(at 0 -1.4 0)
			(layer "B.Fab")
			(hide yes)
			(effects
				(font
					(size 0.7 0.7)
					(thickness 0.15)
				)
				(justify left bottom mirror)
			)
		)
		(property "Description" "1k resistor in 0402 package with 1% tolerance"
			(at 0 0 180)
			(layer "F.Fab")
			(hide yes)
			(effects
				(font
					(size 1.27 1.27)
					(thickness 0.15)
				)
			)
		)
		(property "Author" "Antmicro"
			(at 313.8 169.2 0)
			(layer "B.Fab")
			(hide yes)
			(effects
				(font
					(size 1 1)
					(thickness 0.15)
				)
				(justify mirror)
			)
		)
		(property "License" "Apache-2.0"
			(at 313.8 169.2 0)
			(layer "B.Fab")
			(hide yes)
			(effects
				(font
					(size 1 1)
					(thickness 0.15)
				)
				(justify mirror)
			)
		)
		(property "MPN" "CR0402-FX-1001GLF"
			(at 313.8 169.2 0)
			(layer "B.Fab")
			(hide yes)
			(effects
				(font
					(size 1 1)
					(thickness 0.15)
				)
				(justify mirror)
			)
		)
		(property "Manufacturer" "Bourns"
			(at 313.8 169.2 0)
			(layer "B.Fab")
			(hide yes)
			(effects
				(font
					(size 1 1)
					(thickness 0.15)
				)
				(justify mirror)
			)
		)
		(property "Tolerance" "1%"
			(at 313.8 169.2 0)
			(layer "B.Fab")
			(hide yes)
			(effects
				(font
					(size 1 1)
					(thickness 0.15)
				)
				(justify mirror)
			)
		)
		(property "Val" "1k"
			(at 313.8 169.2 0)
			(layer "B.Fab")
			(hide yes)
			(effects
				(font
					(size 1 1)
					(thickness 0.15)
				)
				(justify mirror)
			)
		)
		(sheetname "DDR5")
		(sheetfile "ddr5.kicad_sch")
		(attr smd)
		(fp_rect
			(start -0.925 0.47)
			(end 0.925 -0.47)
			(stroke
				(width 0.05)
				(type default)
			)
			(fill no)
			(layer "B.CrtYd")
		)
		(fp_rect
			(start -0.5 0.25)
			(end 0.5 -0.25)
			(stroke
				(width 0.15)
				(type solid)
			)
			(fill no)
			(layer "B.Fab")
		)
		(pad "1" smd roundrect
			(at -0.48 0 180)
			(size 0.59 0.64)
			(layers "B.Cu" "B.Mask" "B.Paste")
			(roundrect_rratio 0.25)
			(net 2 "VDDQ")
			(pintype "passive")
		)
		(pad "2" smd roundrect
			(at 0.48 0 180)
			(size 0.59 0.64)
			(layers "B.Cu" "B.Mask" "B.Paste")
			(roundrect_rratio 0.25)
			(net 58 "/DDR5/R_ODT_CA_A")
			(pintype "passive")
		)
	)
	(footprint "antmicro-footprints:C_0201"
		(layer "B.Cu")
		(at 156.5 88.05)
		(descr "Capacitor SMD 0201")
		(tags "capacitor SMD 0201")
		(property "Reference" "C18"
			(at 2.86 0.31 180)
			(layer "B.SilkS")
			(effects
				(font
					(size 0.7 0.7)
					(thickness 0.15)
				)
				(justify left bottom mirror)
			)
		)
		(property "Value" "C_100n_0201"
			(at 0 -1.4 180)
			(layer "B.Fab")
			(hide yes)
			(effects
				(font
					(size 0.7 0.7)
					(thickness 0.15)
				)
				(justify left bottom mirror)
			)
		)
		(property "Description" "SMD Multilayer Ceramic Capacitor, 0.1 µF, 6.3 V, 0201 [0603 Metric], ± 10%, X6S, CC Series"
			(at 0 0 0)
			(layer "F.Fab")
			(hide yes)
			(effects
				(font
					(size 1.27 1.27)
					(thickness 0.15)
				)
			)
		)
		(property "Author" "Antmicro"
			(at 0 0 0)
			(layer "B.Fab")
			(hide yes)
			(effects
				(font
					(size 1 1)
					(thickness 0.15)
				)
				(justify mirror)
			)
		)
		(property "Dielectric" ""
			(at 0 0 0)
			(layer "B.Fab")
			(hide yes)
			(effects
				(font
					(size 1 1)
					(thickness 0.15)
				)
				(justify mirror)
			)
		)
		(property "License" "Apache-2.0"
			(at 0 0 0)
			(layer "B.Fab")
			(hide yes)
			(effects
				(font
					(size 1 1)
					(thickness 0.15)
				)
				(justify mirror)
			)
		)
		(property "MPN" "CC0201KRX6S5BB104"
			(at 0 0 0)
			(layer "B.Fab")
			(hide yes)
			(effects
				(font
					(size 1 1)
					(thickness 0.15)
				)
				(justify mirror)
			)
		)
		(property "Manufacturer" "YAGEO"
			(at 0 0 0)
			(layer "B.Fab")
			(hide yes)
			(effects
				(font
					(size 1 1)
					(thickness 0.15)
				)
				(justify mirror)
			)
		)
		(property "Public" "False"
			(at 0 0 0)
			(layer "B.Fab")
			(hide yes)
			(effects
				(font
					(size 1 1)
					(thickness 0.15)
				)
				(justify mirror)
			)
		)
		(property "Val" "100n"
			(at 0 0 0)
			(layer "B.Fab")
			(hide yes)
			(effects
				(font
					(size 1 1)
					(thickness 0.15)
				)
				(justify mirror)
			)
		)
		(property "Voltage" ""
			(at 0 0 0)
			(layer "B.Fab")
			(hide yes)
			(effects
				(font
					(size 1 1)
					(thickness 0.15)
				)
				(justify mirror)
			)
		)
		(sheetname "DDR5")
		(sheetfile "ddr5.kicad_sch")
		(attr smd)
		(fp_rect
			(start -0.7 0.35)
			(end 0.7 -0.35)
			(stroke
				(width 0.05)
				(type default)
			)
			(fill no)
			(layer "B.CrtYd")
		)
		(fp_rect
			(start 0.3 -0.15)
			(end -0.301 0.149)
			(stroke
				(width 0.15)
				(type solid)
			)
			(fill no)
			(layer "B.Fab")
		)
		(pad "" smd roundrect
			(at -0.349 0.002)
			(size 0.318 0.36)
			(layers "B.Paste")
			(roundrect_rratio 0.25)
		)
		(pad "" smd roundrect
			(at 0.341 0.002)
			(size 0.318 0.36)
			(layers "B.Paste")
			(roundrect_rratio 0.25)
		)
		(pad "1" smd roundrect
			(at -0.321 0.002)
			(size 0.46 0.4)
			(layers "B.Cu" "B.Mask")
			(roundrect_rratio 0.25)
			(net 2 "VDDQ")
			(pintype "passive")
		)
		(pad "2" smd roundrect
			(at 0.32 0.002)
			(size 0.46 0.4)
			(layers "B.Cu" "B.Mask")
			(roundrect_rratio 0.25)
			(net 1 "GND")
			(pintype "passive")
		)
	)
	(footprint "antmicro-footprints:C_0201"
		(layer "B.Cu")
		(at 153.6 80.425 90)
		(descr "Capacitor SMD 0201")
		(tags "capacitor SMD 0201")
		(property "Reference" "C13"
			(at 3.195 0.39 270)
			(layer "B.SilkS")
			(effects
				(font
					(size 0.7 0.7)
					(thickness 0.15)
				)
				(justify left bottom mirror)
			)
		)
		(property "Value" "C_100n_0201"
			(at 0 -1.4 270)
			(layer "B.Fab")
			(hide yes)
			(effects
				(font
					(size 0.7 0.7)
					(thickness 0.15)
				)
				(justify left bottom mirror)
			)
		)
		(property "Description" "SMD Multilayer Ceramic Capacitor, 0.1 µF, 6.3 V, 0201 [0603 Metric], ± 10%, X6S, CC Series"
			(at 0 0 90)
			(layer "F.Fab")
			(hide yes)
			(effects
				(font
					(size 1.27 1.27)
					(thickness 0.15)
				)
			)
		)
		(property "Author" "Antmicro"
			(at 234.025 -73.175 0)
			(layer "B.Fab")
			(hide yes)
			(effects
				(font
					(size 1 1)
					(thickness 0.15)
				)
				(justify mirror)
			)
		)
		(property "Dielectric" ""
			(at 234.025 -73.175 0)
			(layer "B.Fab")
			(hide yes)
			(effects
				(font
					(size 1 1)
					(thickness 0.15)
				)
				(justify mirror)
			)
		)
		(property "License" "Apache-2.0"
			(at 234.025 -73.175 0)
			(layer "B.Fab")
			(hide yes)
			(effects
				(font
					(size 1 1)
					(thickness 0.15)
				)
				(justify mirror)
			)
		)
		(property "MPN" "CC0201KRX6S5BB104"
			(at 234.025 -73.175 0)
			(layer "B.Fab")
			(hide yes)
			(effects
				(font
					(size 1 1)
					(thickness 0.15)
				)
				(justify mirror)
			)
		)
		(property "Manufacturer" "YAGEO"
			(at 234.025 -73.175 0)
			(layer "B.Fab")
			(hide yes)
			(effects
				(font
					(size 1 1)
					(thickness 0.15)
				)
				(justify mirror)
			)
		)
		(property "Public" "False"
			(at 234.025 -73.175 0)
			(layer "B.Fab")
			(hide yes)
			(effects
				(font
					(size 1 1)
					(thickness 0.15)
				)
				(justify mirror)
			)
		)
		(property "Val" "100n"
			(at 234.025 -73.175 0)
			(layer "B.Fab")
			(hide yes)
			(effects
				(font
					(size 1 1)
					(thickness 0.15)
				)
				(justify mirror)
			)
		)
		(property "Voltage" ""
			(at 234.025 -73.175 0)
			(layer "B.Fab")
			(hide yes)
			(effects
				(font
					(size 1 1)
					(thickness 0.15)
				)
				(justify mirror)
			)
		)
		(sheetname "DDR5")
		(sheetfile "ddr5.kicad_sch")
		(attr smd)
		(fp_rect
			(start -0.7 0.35)
			(end 0.7 -0.35)
			(stroke
				(width 0.05)
				(type default)
			)
			(fill no)
			(layer "B.CrtYd")
		)
		(fp_rect
			(start 0.3 -0.15)
			(end -0.301 0.149)
			(stroke
				(width 0.15)
				(type solid)
			)
			(fill no)
			(layer "B.Fab")
		)
		(pad "" smd roundrect
			(at -0.349 0.002 90)
			(size 0.318 0.36)
			(layers "B.Paste")
			(roundrect_rratio 0.25)
		)
		(pad "" smd roundrect
			(at 0.341 0.002 90)
			(size 0.318 0.36)
			(layers "B.Paste")
			(roundrect_rratio 0.25)
		)
		(pad "1" smd roundrect
			(at -0.321 0.002 90)
			(size 0.46 0.4)
			(layers "B.Cu" "B.Mask")
			(roundrect_rratio 0.25)
			(net 2 "VDDQ")
			(pintype "passive")
		)
		(pad "2" smd roundrect
			(at 0.32 0.002 90)
			(size 0.46 0.4)
			(layers "B.Cu" "B.Mask")
			(roundrect_rratio 0.25)
			(net 1 "GND")
			(pintype "passive")
		)
	)
	(footprint "antmicro-footprints:C_0201"
		(layer "B.Cu")
		(at 148.02 80.55 90)
		(descr "Capacitor SMD 0201")
		(tags "capacitor SMD 0201")
		(property "Reference" "C7"
			(at 2.95 0.32 270)
			(layer "B.SilkS")
			(effects
				(font
					(size 0.7 0.7)
					(thickness 0.15)
				)
				(justify left bottom mirror)
			)
		)
		(property "Value" "C_100n_0201"
			(at 0 -1.4 270)
			(layer "B.Fab")
			(hide yes)
			(effects
				(font
					(size 0.7 0.7)
					(thickness 0.15)
				)
				(justify left bottom mirror)
			)
		)
		(property "Description" "SMD Multilayer Ceramic Capacitor, 0.1 µF, 6.3 V, 0201 [0603 Metric], ± 10%, X6S, CC Series"
			(at 0 0 90)
			(layer "F.Fab")
			(hide yes)
			(effects
				(font
					(size 1.27 1.27)
					(thickness 0.15)
				)
			)
		)
		(property "Author" "Antmicro"
			(at 228.57 -67.47 0)
			(layer "B.Fab")
			(hide yes)
			(effects
				(font
					(size 1 1)
					(thickness 0.15)
				)
				(justify mirror)
			)
		)
		(property "Dielectric" ""
			(at 228.57 -67.47 0)
			(layer "B.Fab")
			(hide yes)
			(effects
				(font
					(size 1 1)
					(thickness 0.15)
				)
				(justify mirror)
			)
		)
		(property "License" "Apache-2.0"
			(at 228.57 -67.47 0)
			(layer "B.Fab")
			(hide yes)
			(effects
				(font
					(size 1 1)
					(thickness 0.15)
				)
				(justify mirror)
			)
		)
		(property "MPN" "CC0201KRX6S5BB104"
			(at 228.57 -67.47 0)
			(layer "B.Fab")
			(hide yes)
			(effects
				(font
					(size 1 1)
					(thickness 0.15)
				)
				(justify mirror)
			)
		)
		(property "Manufacturer" "YAGEO"
			(at 228.57 -67.47 0)
			(layer "B.Fab")
			(hide yes)
			(effects
				(font
					(size 1 1)
					(thickness 0.15)
				)
				(justify mirror)
			)
		)
		(property "Public" "False"
			(at 228.57 -67.47 0)
			(layer "B.Fab")
			(hide yes)
			(effects
				(font
					(size 1 1)
					(thickness 0.15)
				)
				(justify mirror)
			)
		)
		(property "Val" "100n"
			(at 228.57 -67.47 0)
			(layer "B.Fab")
			(hide yes)
			(effects
				(font
					(size 1 1)
					(thickness 0.15)
				)
				(justify mirror)
			)
		)
		(property "Voltage" ""
			(at 228.57 -67.47 0)
			(layer "B.Fab")
			(hide yes)
			(effects
				(font
					(size 1 1)
					(thickness 0.15)
				)
				(justify mirror)
			)
		)
		(sheetname "DDR5")
		(sheetfile "ddr5.kicad_sch")
		(attr smd)
		(fp_rect
			(start -0.7 0.35)
			(end 0.7 -0.35)
			(stroke
				(width 0.05)
				(type default)
			)
			(fill no)
			(layer "B.CrtYd")
		)
		(fp_rect
			(start 0.3 -0.15)
			(end -0.301 0.149)
			(stroke
				(width 0.15)
				(type solid)
			)
			(fill no)
			(layer "B.Fab")
		)
		(pad "" smd roundrect
			(at -0.349 0.002 90)
			(size 0.318 0.36)
			(layers "B.Paste")
			(roundrect_rratio 0.25)
		)
		(pad "" smd roundrect
			(at 0.341 0.002 90)
			(size 0.318 0.36)
			(layers "B.Paste")
			(roundrect_rratio 0.25)
		)
		(pad "1" smd roundrect
			(at -0.321 0.002 90)
			(size 0.46 0.4)
			(layers "B.Cu" "B.Mask")
			(roundrect_rratio 0.25)
			(net 2 "VDDQ")
			(pintype "passive")
		)
		(pad "2" smd roundrect
			(at 0.32 0.002 90)
			(size 0.46 0.4)
			(layers "B.Cu" "B.Mask")
			(roundrect_rratio 0.25)
			(net 1 "GND")
			(pintype "passive")
		)
	)
)
